(kicad_pcb
	(version 20260206)
	(generator "pcbnew")
	(generator_version "10.0")
	(general
		(thickness 1.6)
		(legacy_teardrops no)
	)
	(paper "A4")
	(title_block
		(title "04192023_DAF0TMB3IC0_F0TG_MB_C_brd_V02_OCP.brd")
		(comment 1 "Grand Teton / footprints 960-967 of 8354")
	)
	(layers
		(0 "F.Cu" signal "TOP")
		(4 "In1.Cu" signal "GND")
		(6 "In2.Cu" signal "IN1")
		(8 "In3.Cu" signal "GND1")
		(10 "In4.Cu" signal "IN2")
		(12 "In5.Cu" signal "GND2")
		(14 "In6.Cu" signal "IN3")
		(16 "In7.Cu" signal "GND3")
		(18 "In8.Cu" signal "VCC")
		(20 "In9.Cu" signal "VCC1")
		(22 "In10.Cu" signal "GND4")
		(24 "In11.Cu" signal "IN4")
		(26 "In12.Cu" signal "GND5")
		(28 "In13.Cu" signal "IN5")
		(30 "In14.Cu" signal "GND6")
		(32 "In15.Cu" signal "IN6")
		(34 "In16.Cu" signal "GND7")
		(2 "B.Cu" signal "BOTTOM")
		(9 "F.Adhes" user "F.Adhesive")
		(11 "B.Adhes" user "B.Adhesive")
		(13 "F.Paste" user "Package Geometry/Pastemask Top")
		(15 "B.Paste" user "Package Geometry/Pastemask Bottom")
		(5 "F.SilkS" user "Ref Des/Silkscreen Top")
		(7 "B.SilkS" user "Ref Des/Silkscreen Bottom")
		(1 "F.Mask" user "Board Geometry/Soldermask Top")
		(3 "B.Mask" user "Board Geometry/Soldermask Bottom")
		(17 "Dwgs.User" user "User.Drawings")
		(19 "Cmts.User" user "User.Comments")
		(21 "Eco1.User" user "User.Eco1")
		(23 "Eco2.User" user "User.Eco2")
		(25 "Edge.Cuts" user "Board Geometry/Outline")
		(27 "Margin" user)
		(31 "F.CrtYd" user "Package Geometry/Place Bound Top")
		(29 "B.CrtYd" user "Package Geometry/Place Bound Bottom")
		(35 "F.Fab" user "Ref Des/Assembly Top")
		(33 "B.Fab" user "Ref Des/Assembly Bottom")
	)
	(footprint ""
		(layer "F.Cu")
		(at 192.599818 -70.185788)
		(property "Reference" "PR3947"
			(at 0 0 0)
			(layer "F.SilkS")
			(hide yes)
			(effects
				(font
					(size 1.27 1.27)
				)
			)
		)
		(property "Value" ""
			(at 0 0 0)
			(layer "F.Fab")
			(effects
				(font
					(size 1.27 1.27)
				)
			)
		)
		(duplicate_pad_numbers_are_jumpers no)
		(fp_line
			(start -0.7874 -0.4064)
			(end 0.7874 -0.4064)
			(stroke
				(width 0.1524)
				(type default)
			)
			(layer "F.SilkS")
		)
		(fp_line
			(start -0.7874 0.4064)
			(end -0.7874 -0.4064)
			(stroke
				(width 0.1524)
				(type default)
			)
			(layer "F.SilkS")
		)
		(fp_line
			(start 0.7874 -0.4064)
			(end 0.7874 0.4064)
			(stroke
				(width 0.1524)
				(type default)
			)
			(layer "F.SilkS")
		)
		(fp_line
			(start 0.7874 0.4064)
			(end -0.7874 0.4064)
			(stroke
				(width 0.1524)
				(type default)
			)
			(layer "F.SilkS")
		)
		(fp_line
			(start -0.67945 -0.305054)
			(end -0.12065 -0.305054)
			(stroke
				(width 0.1)
				(type default)
			)
			(layer "F.Fab")
		)
		(fp_line
			(start -0.67945 0.3048)
			(end -0.67945 -0.305054)
			(stroke
				(width 0.1)
				(type default)
			)
			(layer "F.Fab")
		)
		(fp_line
			(start -0.12065 -0.305054)
			(end -0.12065 -0.2794)
			(stroke
				(width 0.1)
				(type default)
			)
			(layer "F.Fab")
		)
		(fp_line
			(start -0.12065 -0.2794)
			(end 0.12065 -0.2794)
			(stroke
				(width 0.1)
				(type default)
			)
			(layer "F.Fab")
		)
		(fp_line
			(start -0.12065 0.2794)
			(end -0.12065 0.3048)
			(stroke
				(width 0.1)
				(type default)
			)
			(layer "F.Fab")
		)
		(fp_line
			(start -0.12065 0.3048)
			(end -0.67945 0.3048)
			(stroke
				(width 0.1)
				(type default)
			)
			(layer "F.Fab")
		)
		(fp_line
			(start 0.120396 0.2794)
			(end -0.12065 0.2794)
			(stroke
				(width 0.1)
				(type default)
			)
			(layer "F.Fab")
		)
		(fp_line
			(start 0.120396 0.3048)
			(end 0.120396 0.2794)
			(stroke
				(width 0.1)
				(type default)
			)
			(layer "F.Fab")
		)
		(fp_line
			(start 0.12065 -0.3048)
			(end 0.67945 -0.3048)
			(stroke
				(width 0.1)
				(type default)
			)
			(layer "F.Fab")
		)
		(fp_line
			(start 0.12065 -0.2794)
			(end 0.12065 -0.3048)
			(stroke
				(width 0.1)
				(type default)
			)
			(layer "F.Fab")
		)
		(fp_line
			(start 0.67945 -0.3048)
			(end 0.67945 0.3048)
			(stroke
				(width 0.1)
				(type default)
			)
			(layer "F.Fab")
		)
		(fp_line
			(start 0.67945 0.3048)
			(end 0.120396 0.3048)
			(stroke
				(width 0.1)
				(type default)
			)
			(layer "F.Fab")
		)
		(pad "1" smd circle
			(at -0.40005 0)
			(size 0 0)
			(layers "F.Cu" "F.Mask" "F.Paste")
			(net "GND")
		)
		(pad "2" smd circle
			(at 0.40005 0)
			(size 0 0)
			(layers "F.Cu" "F.Mask" "F.Paste")
			(net "P3V3_E1S_ILIMIT_0")
		)
	)
	(footprint ""
		(layer "F.Cu")
		(at 197.269608 -111.593376 180)
		(property "Reference" "R177"
			(at 0 0 180)
			(layer "F.SilkS")
			(hide yes)
			(effects
				(font
					(size 1.27 1.27)
				)
			)
		)
		(property "Value" ""
			(at 0 0 180)
			(layer "F.Fab")
			(effects
				(font
					(size 1.27 1.27)
				)
			)
		)
		(duplicate_pad_numbers_are_jumpers no)
		(fp_line
			(start 0.7874 0.4064)
			(end -0.7874 0.4064)
			(stroke
				(width 0.1524)
				(type default)
			)
			(layer "F.SilkS")
		)
		(fp_line
			(start 0.7874 -0.4064)
			(end 0.7874 0.4064)
			(stroke
				(width 0.1524)
				(type default)
			)
			(layer "F.SilkS")
		)
		(fp_line
			(start -0.7874 0.4064)
			(end -0.7874 -0.4064)
			(stroke
				(width 0.1524)
				(type default)
			)
			(layer "F.SilkS")
		)
		(fp_line
			(start -0.7874 -0.4064)
			(end 0.7874 -0.4064)
			(stroke
				(width 0.1524)
				(type default)
			)
			(layer "F.SilkS")
		)
		(fp_line
			(start 0.67945 0.3048)
			(end 0.120396 0.3048)
			(stroke
				(width 0.1)
				(type default)
			)
			(layer "F.Fab")
		)
		(fp_line
			(start 0.67945 -0.3048)
			(end 0.67945 0.3048)
			(stroke
				(width 0.1)
				(type default)
			)
			(layer "F.Fab")
		)
		(fp_line
			(start 0.12065 -0.2794)
			(end 0.12065 -0.3048)
			(stroke
				(width 0.1)
				(type default)
			)
			(layer "F.Fab")
		)
		(fp_line
			(start 0.12065 -0.3048)
			(end 0.67945 -0.3048)
			(stroke
				(width 0.1)
				(type default)
			)
			(layer "F.Fab")
		)
		(fp_line
			(start 0.120396 0.3048)
			(end 0.120396 0.2794)
			(stroke
				(width 0.1)
				(type default)
			)
			(layer "F.Fab")
		)
		(fp_line
			(start 0.120396 0.2794)
			(end -0.12065 0.2794)
			(stroke
				(width 0.1)
				(type default)
			)
			(layer "F.Fab")
		)
		(fp_line
			(start -0.12065 0.3048)
			(end -0.67945 0.3048)
			(stroke
				(width 0.1)
				(type default)
			)
			(layer "F.Fab")
		)
		(fp_line
			(start -0.12065 0.2794)
			(end -0.12065 0.3048)
			(stroke
				(width 0.1)
				(type default)
			)
			(layer "F.Fab")
		)
		(fp_line
			(start -0.12065 -0.2794)
			(end 0.12065 -0.2794)
			(stroke
				(width 0.1)
				(type default)
			)
			(layer "F.Fab")
		)
		(fp_line
			(start -0.12065 -0.305054)
			(end -0.12065 -0.2794)
			(stroke
				(width 0.1)
				(type default)
			)
			(layer "F.Fab")
		)
		(fp_line
			(start -0.67945 0.3048)
			(end -0.67945 -0.305054)
			(stroke
				(width 0.1)
				(type default)
			)
			(layer "F.Fab")
		)
		(fp_line
			(start -0.67945 -0.305054)
			(end -0.12065 -0.305054)
			(stroke
				(width 0.1)
				(type default)
			)
			(layer "F.Fab")
		)
		(pad "1" smd circle
			(at -0.40005 0 180)
			(size 0 0)
			(layers "F.Cu" "F.Mask" "F.Paste")
			(net "PWRGD_PVDD18_S5_P0")
		)
		(pad "2" smd circle
			(at 0.40005 0 180)
			(size 0 0)
			(layers "F.Cu" "F.Mask" "F.Paste")
			(net "FM_PWRGD_PVDD18_S5_P0")
		)
	)
	(footprint ""
		(layer "F.Cu")
		(at 77.915262 -30.112462 -90)
		(property "Reference" "PD107"
			(at 2.145792 -2.517648 90)
			(unlocked yes)
			(layer "F.SilkS")
			(effects
				(font
					(size 0.7874 0.5842)
					(thickness 0.1524)
				)
				(justify left)
			)
		)
		(property "Value" ""
			(at 0 0 270)
			(layer "F.Fab")
			(effects
				(font
					(size 1.27 1.27)
				)
			)
		)
		(duplicate_pad_numbers_are_jumpers no)
		(fp_line
			(start -2.250186 0.999998)
			(end 2.631186 0.999998)
			(stroke
				(width 0.1524)
				(type default)
			)
			(layer "F.SilkS")
		)
		(fp_line
			(start 2.631186 0.999998)
			(end 2.631186 -0.999998)
			(stroke
				(width 0.1524)
				(type default)
			)
			(layer "F.SilkS")
		)
		(fp_line
			(start -0.381 0.3302)
			(end -0.381 -0.4318)
			(stroke
				(width 0.1524)
				(type default)
			)
			(layer "F.SilkS")
		)
		(fp_line
			(start -0.381 -0.0508)
			(end -0.6604 -0.0508)
			(stroke
				(width 0.1524)
				(type default)
			)
			(layer "F.SilkS")
		)
		(fp_line
			(start 0.381 -0.0508)
			(end -0.381 0.3302)
			(stroke
				(width 0.1524)
				(type default)
			)
			(layer "F.SilkS")
		)
		(fp_line
			(start 0.381 -0.0508)
			(end 0.635 -0.0508)
			(stroke
				(width 0.1524)
				(type default)
			)
			(layer "F.SilkS")
		)
		(fp_line
			(start -0.381 -0.4318)
			(end 0.381 -0.0508)
			(stroke
				(width 0.1524)
				(type default)
			)
			(layer "F.SilkS")
		)
		(fp_line
			(start 0.381 -0.4318)
			(end 0.381 0.3302)
			(stroke
				(width 0.1524)
				(type default)
			)
			(layer "F.SilkS")
		)
		(fp_line
			(start -2.250186 -0.999998)
			(end -2.250186 0.999998)
			(stroke
				(width 0.1524)
				(type default)
			)
			(layer "F.SilkS")
		)
		(fp_line
			(start 2.631186 -0.999998)
			(end -2.250186 -0.999998)
			(stroke
				(width 0.1524)
				(type default)
			)
			(layer "F.SilkS")
		)
		(fp_rect
			(start 2.6162 1.016)
			(end 2.1844 -0.9652)
			(stroke
				(width 0)
				(type default)
			)
			(fill yes)
			(layer "F.SilkS")
		)
		(fp_line
			(start -1.450086 0.999998)
			(end 1.450086 0.999998)
			(stroke
				(width 0.1)
				(type default)
			)
			(layer "F.Fab")
		)
		(fp_line
			(start 1.450086 0.999998)
			(end 1.450086 -0.999998)
			(stroke
				(width 0.1)
				(type default)
			)
			(layer "F.Fab")
		)
		(fp_line
			(start -1.450086 -0.999998)
			(end -1.450086 0.999998)
			(stroke
				(width 0.1)
				(type default)
			)
			(layer "F.Fab")
		)
		(fp_line
			(start 1.450086 -0.999998)
			(end -1.450086 -0.999998)
			(stroke
				(width 0.1)
				(type default)
			)
			(layer "F.Fab")
		)
		(fp_text user "+"
			(at -3.849878 -0.100584 270)
			(unlocked yes)
			(layer "F.SilkS")
			(effects
				(font
					(size 1.905 1.4224)
					(thickness 0.1524)
				)
				(justify left)
			)
		)
		(fp_text user "-"
			(at 2.4384 -0.22225 270)
			(unlocked yes)
			(layer "F.SilkS")
			(effects
				(font
					(size 1.905 1.4224)
					(thickness 0.1524)
				)
				(justify left)
			)
		)
		(fp_text user "+"
			(at -3.4798 -0.22225 270)
			(unlocked yes)
			(layer "F.Fab")
			(effects
				(font
					(size 1.905 1.4224)
					(thickness 0.1524)
				)
				(justify left)
			)
		)
		(fp_text user "-"
			(at 2.4384 -0.22225 270)
			(unlocked yes)
			(layer "F.Fab")
			(effects
				(font
					(size 1.905 1.4224)
					(thickness 0.1524)
				)
				(justify left)
			)
		)
		(pad "A" smd rect
			(at -1.450086 0 270)
			(size 1.3208 1.4224)
			(layers "F.Cu" "F.Mask" "F.Paste")
			(net "GND")
		)
		(pad "C" smd rect
			(at 1.450086 0 270)
			(size 1.3208 1.4224)
			(layers "F.Cu" "F.Mask" "F.Paste")
			(net "P12V_AUX")
		)
	)
	(footprint ""
		(layer "F.Cu")
		(at 381.762 -103.378)
		(property "Reference" "ME15"
			(at 0 0 0)
			(layer "F.SilkS")
			(hide yes)
			(effects
				(font
					(size 1.27 1.27)
				)
			)
		)
		(property "Value" ""
			(at 0 0 0)
			(layer "F.Fab")
			(effects
				(font
					(size 1.27 1.27)
				)
			)
		)
		(duplicate_pad_numbers_are_jumpers no)
		(zone
			(layer "F.Cu")
			(hatch none 0.5)
			(connect_pads
				(clearance 0)
			)
			(min_thickness 0.25)
			(keepout
				(tracks allowed)
				(vias allowed)
				(pads allowed)
				(copperpour allowed)
				(footprints not_allowed)
			)
			(placement
				(enabled no)
				(sheetname "")
			)
			(fill
				(thermal_gap 0.5)
				(thermal_bridge_width 0.5)
				(island_removal_mode 0)
			)
			(polygon
				(pts
					(arc
						(start 391.76198 -103.378)
						(mid 371.76202 -103.378)
						(end 391.76198 -103.378)
					)
				)
			)
		)
	)
	(footprint ""
		(layer "F.Cu")
		(at 448.980052 -18.063464 -90)
		(property "Reference" "PR3787"
			(at 0 0 270)
			(layer "F.SilkS")
			(hide yes)
			(effects
				(font
					(size 1.27 1.27)
				)
			)
		)
		(property "Value" ""
			(at 0 0 270)
			(layer "F.Fab")
			(effects
				(font
					(size 1.27 1.27)
				)
			)
		)
		(duplicate_pad_numbers_are_jumpers no)
		(fp_line
			(start -0.7874 0.4064)
			(end -0.7874 -0.4064)
			(stroke
				(width 0.1524)
				(type default)
			)
			(layer "F.SilkS")
		)
		(fp_line
			(start 0.7874 0.4064)
			(end -0.7874 0.4064)
			(stroke
				(width 0.1524)
				(type default)
			)
			(layer "F.SilkS")
		)
		(fp_line
			(start -0.7874 -0.4064)
			(end 0.7874 -0.4064)
			(stroke
				(width 0.1524)
				(type default)
			)
			(layer "F.SilkS")
		)
		(fp_line
			(start 0.7874 -0.4064)
			(end 0.7874 0.4064)
			(stroke
				(width 0.1524)
				(type default)
			)
			(layer "F.SilkS")
		)
		(fp_line
			(start -0.67945 0.3048)
			(end -0.67945 -0.305054)
			(stroke
				(width 0.1)
				(type default)
			)
			(layer "F.Fab")
		)
		(fp_line
			(start -0.12065 0.3048)
			(end -0.67945 0.3048)
			(stroke
				(width 0.1)
				(type default)
			)
			(layer "F.Fab")
		)
		(fp_line
			(start 0.120396 0.3048)
			(end 0.120396 0.2794)
			(stroke
				(width 0.1)
				(type default)
			)
			(layer "F.Fab")
		)
		(fp_line
			(start 0.67945 0.3048)
			(end 0.120396 0.3048)
			(stroke
				(width 0.1)
				(type default)
			)
			(layer "F.Fab")
		)
		(fp_line
			(start -0.12065 0.2794)
			(end -0.12065 0.3048)
			(stroke
				(width 0.1)
				(type default)
			)
			(layer "F.Fab")
		)
		(fp_line
			(start 0.120396 0.2794)
			(end -0.12065 0.2794)
			(stroke
				(width 0.1)
				(type default)
			)
			(layer "F.Fab")
		)
		(fp_line
			(start -0.12065 -0.2794)
			(end 0.12065 -0.2794)
			(stroke
				(width 0.1)
				(type default)
			)
			(layer "F.Fab")
		)
		(fp_line
			(start 0.12065 -0.2794)
			(end 0.12065 -0.3048)
			(stroke
				(width 0.1)
				(type default)
			)
			(layer "F.Fab")
		)
		(fp_line
			(start 0.12065 -0.3048)
			(end 0.67945 -0.3048)
			(stroke
				(width 0.1)
				(type default)
			)
			(layer "F.Fab")
		)
		(fp_line
			(start 0.67945 -0.3048)
			(end 0.67945 0.3048)
			(stroke
				(width 0.1)
				(type default)
			)
			(layer "F.Fab")
		)
		(fp_line
			(start -0.67945 -0.305054)
			(end -0.12065 -0.305054)
			(stroke
				(width 0.1)
				(type default)
			)
			(layer "F.Fab")
		)
		(fp_line
			(start -0.12065 -0.305054)
			(end -0.12065 -0.2794)
			(stroke
				(width 0.1)
				(type default)
			)
			(layer "F.Fab")
		)
		(pad "1" smd circle
			(at -0.40005 0 270)
			(size 0 0)
			(layers "F.Cu" "F.Mask" "F.Paste")
			(net "P12V_OCP_UV_1")
		)
		(pad "2" smd circle
			(at 0.40005 0 270)
			(size 0 0)
			(layers "F.Cu" "F.Mask" "F.Paste")
			(net "P12V_OCP_OV_1")
		)
	)
	(footprint ""
		(layer "F.Cu")
		(at 364.84179 -392.1252)
		(property "Reference" "R1119"
			(at 0 0 0)
			(layer "F.SilkS")
			(hide yes)
			(effects
				(font
					(size 1.27 1.27)
				)
			)
		)
		(property "Value" ""
			(at 0 0 0)
			(layer "F.Fab")
			(effects
				(font
					(size 1.27 1.27)
				)
			)
		)
		(duplicate_pad_numbers_are_jumpers no)
		(fp_line
			(start -0.32512 -0.175006)
			(end 0.32512 -0.175006)
			(stroke
				(width 0.1)
				(type default)
			)
			(layer "F.Fab")
		)
		(fp_line
			(start -0.32512 0.175006)
			(end -0.32512 -0.175006)
			(stroke
				(width 0.1)
				(type default)
			)
			(layer "F.Fab")
		)
		(fp_line
			(start 0.32512 -0.175006)
			(end 0.32512 0.175006)
			(stroke
				(width 0.1)
				(type default)
			)
			(layer "F.Fab")
		)
		(fp_line
			(start 0.32512 0.175006)
			(end -0.32512 0.175006)
			(stroke
				(width 0.1)
				(type default)
			)
			(layer "F.Fab")
		)
		(pad "1" smd rect
			(at -0.2667 0)
			(size 0.3048 0.381)
			(layers "F.Cu" "F.Mask" "F.Paste")
			(net "P1V8_CPU0_RT_1D")
		)
		(pad "2" smd rect
			(at 0.2667 0 180)
			(size 0.3048 0.381)
			(layers "F.Cu" "F.Mask" "F.Paste")
			(net "TEST2_RT_CPU0_P3")
		)
	)
	(footprint ""
		(layer "F.Cu")
		(at 369.687094 -403.603206 -90)
		(property "Reference" "R1121"
			(at 0 0 270)
			(layer "F.SilkS")
			(hide yes)
			(effects
				(font
					(size 1.27 1.27)
				)
			)
		)
		(property "Value" ""
			(at 0 0 270)
			(layer "F.Fab")
			(effects
				(font
					(size 1.27 1.27)
				)
			)
		)
		(duplicate_pad_numbers_are_jumpers no)
		(fp_line
			(start -0.32512 0.175006)
			(end -0.32512 -0.175006)
			(stroke
				(width 0.1)
				(type default)
			)
			(layer "F.Fab")
		)
		(fp_line
			(start 0.32512 0.175006)
			(end -0.32512 0.175006)
			(stroke
				(width 0.1)
				(type default)
			)
			(layer "F.Fab")
		)
		(fp_line
			(start -0.32512 -0.175006)
			(end 0.32512 -0.175006)
			(stroke
				(width 0.1)
				(type default)
			)
			(layer "F.Fab")
		)
		(fp_line
			(start 0.32512 -0.175006)
			(end 0.32512 0.175006)
			(stroke
				(width 0.1)
				(type default)
			)
			(layer "F.Fab")
		)
		(pad "1" smd rect
			(at -0.2667 0 270)
			(size 0.3048 0.381)
			(layers "F.Cu" "F.Mask" "F.Paste")
			(net "JTAG_TEST_MODE_RT_CPU0_P3")
		)
		(pad "2" smd rect
			(at 0.2667 0 90)
			(size 0.3048 0.381)
			(layers "F.Cu" "F.Mask" "F.Paste")
			(net "GND")
		)
	)
	(footprint ""
		(layer "F.Cu")
		(at 311.541922 -32.572706)
		(property "Reference" "R3859"
			(at 0 0 0)
			(layer "F.SilkS")
			(hide yes)
			(effects
				(font
					(size 1.27 1.27)
				)
			)
		)
		(property "Value" ""
			(at 0 0 0)
			(layer "F.Fab")
			(effects
				(font
					(size 1.27 1.27)
				)
			)
		)
		(duplicate_pad_numbers_are_jumpers no)
		(fp_line
			(start -0.7874 -0.4064)
			(end 0.7874 -0.4064)
			(stroke
				(width 0.1524)
				(type default)
			)
			(layer "F.SilkS")
		)
		(fp_line
			(start -0.7874 0.4064)
			(end -0.7874 -0.4064)
			(stroke
				(width 0.1524)
				(type default)
			)
			(layer "F.SilkS")
		)
		(fp_line
			(start 0.7874 -0.4064)
			(end 0.7874 0.4064)
			(stroke
				(width 0.1524)
				(type default)
			)
			(layer "F.SilkS")
		)
		(fp_line
			(start 0.7874 0.4064)
			(end -0.7874 0.4064)
			(stroke
				(width 0.1524)
				(type default)
			)
			(layer "F.SilkS")
		)
		(fp_line
			(start -0.67945 -0.305054)
			(end -0.12065 -0.305054)
			(stroke
				(width 0.1)
				(type default)
			)
			(layer "F.Fab")
		)
		(fp_line
			(start -0.67945 0.3048)
			(end -0.67945 -0.305054)
			(stroke
				(width 0.1)
				(type default)
			)
			(layer "F.Fab")
		)
		(fp_line
			(start -0.12065 -0.305054)
			(end -0.12065 -0.2794)
			(stroke
				(width 0.1)
				(type default)
			)
			(layer "F.Fab")
		)
		(fp_line
			(start -0.12065 -0.2794)
			(end 0.12065 -0.2794)
			(stroke
				(width 0.1)
				(type default)
			)
			(layer "F.Fab")
		)
		(fp_line
			(start -0.12065 0.2794)
			(end -0.12065 0.3048)
			(stroke
				(width 0.1)
				(type default)
			)
			(layer "F.Fab")
		)
		(fp_line
			(start -0.12065 0.3048)
			(end -0.67945 0.3048)
			(stroke
				(width 0.1)
				(type default)
			)
			(layer "F.Fab")
		)
		(fp_line
			(start 0.120396 0.2794)
			(end -0.12065 0.2794)
			(stroke
				(width 0.1)
				(type default)
			)
			(layer "F.Fab")
		)
		(fp_line
			(start 0.120396 0.3048)
			(end 0.120396 0.2794)
			(stroke
				(width 0.1)
				(type default)
			)
			(layer "F.Fab")
		)
		(fp_line
			(start 0.12065 -0.3048)
			(end 0.67945 -0.3048)
			(stroke
				(width 0.1)
				(type default)
			)
			(layer "F.Fab")
		)
		(fp_line
			(start 0.12065 -0.2794)
			(end 0.12065 -0.3048)
			(stroke
				(width 0.1)
				(type default)
			)
			(layer "F.Fab")
		)
		(fp_line
			(start 0.67945 -0.3048)
			(end 0.67945 0.3048)
			(stroke
				(width 0.1)
				(type default)
			)
			(layer "F.Fab")
		)
		(fp_line
			(start 0.67945 0.3048)
			(end 0.120396 0.3048)
			(stroke
				(width 0.1)
				(type default)
			)
			(layer "F.Fab")
		)
		(pad "1" smd rect
			(at -0.40005 0 180)
			(size 0.4572 0.508)
			(layers "F.Cu" "F.Mask" "F.Paste")
			(net "P12V_OCP_V3_2_ISENSE_MAM_MAM")
		)
		(pad "2" smd rect
			(at 0.40005 0 180)
			(size 0.4572 0.508)
			(layers "F.Cu" "F.Mask" "F.Paste")
			(net "P12V_OCP_V3_2_ISENSE_MAM")
		)
	)
)
